# T6G (Grand Teton) — schematic netlist excerpt (pin names and nets, part order shuffled) for the footprints in the layout excerpt that follows; sources: Cadence DE-HDL packaged netlist, KiCad conversion of 04192023_DAF0TMB3IC0_F0TG_MB_C_brd_V02_OCP.brd

C818  Q_CAP_DIFFBUS  DIFF BUS_0.22UF 6.3V 20% X6S  pkg C0201  page 65 : \1\ = P5E_CPU1_P0_TX_C_DN<9> ; \2\ = P5E_CPU1_P0_TX_DN<9>
R8156  Q_RES  1K 1% EMPTY  pkg 0402LF  page 210 : A = PVDD18_S5_P1 ; B = SVID_PVDDCR_CPU0_P1_SVD_R
C6697  Q_CAP_DIFFBUS  DIFF BUS_0.22UF 6.3V 20% X6S  pkg C0201  page 341 : \1\ = P5E_CPU1_P2_TX_BUF_C_DP<2> ; \2\ = P5E_CPU1_P2_TX_BUF_DP<2>

(kicad_pcb
	(version 20260206)
	(generator "pcbnew")
	(generator_version "10.0")
	(general
		(thickness 1.6)
		(legacy_teardrops no)
	)
	(paper "A4")
	(title_block
		(title "04192023_DAF0TMB3IC0_F0TG_MB_C_brd_V02_OCP.brd")
		(comment 1 "Grand Teton / footprints 1884-1886 of 8354")
	)
	(layers
		(0 "F.Cu" signal "TOP")
		(4 "In1.Cu" signal "GND")
		(6 "In2.Cu" signal "IN1")
		(8 "In3.Cu" signal "GND1")
		(10 "In4.Cu" signal "IN2")
		(12 "In5.Cu" signal "GND2")
		(14 "In6.Cu" signal "IN3")
		(16 "In7.Cu" signal "GND3")
		(18 "In8.Cu" signal "VCC")
		(20 "In9.Cu" signal "VCC1")
		(22 "In10.Cu" signal "GND4")
		(24 "In11.Cu" signal "IN4")
		(26 "In12.Cu" signal "GND5")
		(28 "In13.Cu" signal "IN5")
		(30 "In14.Cu" signal "GND6")
		(32 "In15.Cu" signal "IN6")
		(34 "In16.Cu" signal "GND7")
		(2 "B.Cu" signal "BOTTOM")
		(9 "F.Adhes" user "F.Adhesive")
		(11 "B.Adhes" user "B.Adhesive")
		(13 "F.Paste" user "Package Geometry/Pastemask Top")
		(15 "B.Paste" user "Package Geometry/Pastemask Bottom")
		(5 "F.SilkS" user "Ref Des/Silkscreen Top")
		(7 "B.SilkS" user "Ref Des/Silkscreen Bottom")
		(1 "F.Mask" user "Board Geometry/Soldermask Top")
		(3 "B.Mask" user "Board Geometry/Soldermask Bottom")
		(17 "Dwgs.User" user "User.Drawings")
		(19 "Cmts.User" user "User.Comments")
		(21 "Eco1.User" user "User.Eco1")
		(23 "Eco2.User" user "User.Eco2")
		(25 "Edge.Cuts" user "Board Geometry/Outline")
		(27 "Margin" user)
		(31 "F.CrtYd" user "Package Geometry/Place Bound Top")
		(29 "B.CrtYd" user "Package Geometry/Place Bound Bottom")
		(35 "F.Fab" user "Ref Des/Assembly Top")
		(33 "B.Fab" user "Ref Des/Assembly Bottom")
	)
	(footprint ""
		(layer "F.Cu")
		(at 121.909586 -408.517344 -90)
		(property "Reference" "C6697"
			(at 0 0 270)
			(layer "F.SilkS")
			(hide yes)
			(effects
				(font
					(size 1.27 1.27)
				)
			)
		)
		(property "Value" ""
			(at 0 0 270)
			(layer "F.Fab")
			(effects
				(font
					(size 1.27 1.27)
				)
			)
		)
		(duplicate_pad_numbers_are_jumpers no)
		(fp_line
			(start -0.299974 0.150114)
			(end -0.299974 -0.150114)
			(stroke
				(width 0.1)
				(type default)
			)
			(layer "F.Fab")
		)
		(fp_line
			(start 0.299974 0.150114)
			(end -0.299974 0.150114)
			(stroke
				(width 0.1)
				(type default)
			)
			(layer "F.Fab")
		)
		(fp_line
			(start -0.299974 -0.150114)
			(end 0.299974 -0.150114)
			(stroke
				(width 0.1)
				(type default)
			)
			(layer "F.Fab")
		)
		(fp_line
			(start 0.299974 -0.150114)
			(end 0.299974 0.150114)
			(stroke
				(width 0.1)
				(type default)
			)
			(layer "F.Fab")
		)
		(pad "1" smd rect
			(at -0.2667 0 270)
			(size 0.3048 0.381)
			(layers "F.Cu" "F.Mask" "F.Paste")
			(net "P5E_CPU1_P2_TX_BUF_C_DP<2>")
		)
		(pad "2" smd rect
			(at 0.2667 0 270)
			(size 0.3048 0.381)
			(layers "F.Cu" "F.Mask" "F.Paste")
			(net "P5E_CPU1_P2_TX_BUF_DP<2>")
		)
	)
	(footprint ""
		(layer "F.Cu")
		(at 59.220354 -370.57203 -90)
		(property "Reference" "C818"
			(at 0 0 270)
			(layer "F.SilkS")
			(hide yes)
			(effects
				(font
					(size 1.27 1.27)
				)
			)
		)
		(property "Value" ""
			(at 0 0 270)
			(layer "F.Fab")
			(effects
				(font
					(size 1.27 1.27)
				)
			)
		)
		(duplicate_pad_numbers_are_jumpers no)
		(fp_line
			(start -0.299974 0.150114)
			(end -0.299974 -0.150114)
			(stroke
				(width 0.1)
				(type default)
			)
			(layer "F.Fab")
		)
		(fp_line
			(start 0.299974 0.150114)
			(end -0.299974 0.150114)
			(stroke
				(width 0.1)
				(type default)
			)
			(layer "F.Fab")
		)
		(fp_line
			(start -0.299974 -0.150114)
			(end 0.299974 -0.150114)
			(stroke
				(width 0.1)
				(type default)
			)
			(layer "F.Fab")
		)
		(fp_line
			(start 0.299974 -0.150114)
			(end 0.299974 0.150114)
			(stroke
				(width 0.1)
				(type default)
			)
			(layer "F.Fab")
		)
		(pad "1" smd rect
			(at -0.2667 0 270)
			(size 0.3048 0.381)
			(layers "F.Cu" "F.Mask" "F.Paste")
			(net "P5E_CPU1_P0_TX_C_DN<9>")
		)
		(pad "2" smd rect
			(at 0.2667 0 270)
			(size 0.3048 0.381)
			(layers "F.Cu" "F.Mask" "F.Paste")
			(net "P5E_CPU1_P0_TX_DN<9>")
		)
	)
	(footprint ""
		(layer "F.Cu")
		(at 90.209878 -146.91741 180)
		(property "Reference" "R8156"
			(at 0 0 180)
			(layer "F.SilkS")
			(hide yes)
			(effects
				(font
					(size 1.27 1.27)
				)
			)
		)
		(property "Value" ""
			(at 0 0 180)
			(layer "F.Fab")
			(effects
				(font
					(size 1.27 1.27)
				)
			)
		)
		(duplicate_pad_numbers_are_jumpers no)
		(fp_line
			(start 0.7874 0.4064)
			(end -0.7874 0.4064)
			(stroke
				(width 0.1524)
				(type default)
			)
			(layer "F.SilkS")
		)
		(fp_line
			(start 0.7874 -0.4064)
			(end 0.7874 0.4064)
			(stroke
				(width 0.1524)
				(type default)
			)
			(layer "F.SilkS")
		)
		(fp_line
			(start -0.7874 0.4064)
			(end -0.7874 -0.4064)
			(stroke
				(width 0.1524)
				(type default)
			)
			(layer "F.SilkS")
		)
		(fp_line
			(start -0.7874 -0.4064)
			(end 0.7874 -0.4064)
			(stroke
				(width 0.1524)
				(type default)
			)
			(layer "F.SilkS")
		)
		(fp_line
			(start 0.67945 0.3048)
			(end 0.120396 0.3048)
			(stroke
				(width 0.1)
				(type default)
			)
			(layer "F.Fab")
		)
		(fp_line
			(start 0.67945 -0.3048)
			(end 0.67945 0.3048)
			(stroke
				(width 0.1)
				(type default)
			)
			(layer "F.Fab")
		)
		(fp_line
			(start 0.12065 -0.2794)
			(end 0.12065 -0.3048)
			(stroke
				(width 0.1)
				(type default)
			)
			(layer "F.Fab")
		)
		(fp_line
			(start 0.12065 -0.3048)
			(end 0.67945 -0.3048)
			(stroke
				(width 0.1)
				(type default)
			)
			(layer "F.Fab")
		)
		(fp_line
			(start 0.120396 0.3048)
			(end 0.120396 0.2794)
			(stroke
				(width 0.1)
				(type default)
			)
			(layer "F.Fab")
		)
		(fp_line
			(start 0.120396 0.2794)
			(end -0.12065 0.2794)
			(stroke
				(width 0.1)
				(type default)
			)
			(layer "F.Fab")
		)
		(fp_line
			(start -0.12065 0.3048)
			(end -0.67945 0.3048)
			(stroke
				(width 0.1)
				(type default)
			)
			(layer "F.Fab")
		)
		(fp_line
			(start -0.12065 0.2794)
			(end -0.12065 0.3048)
			(stroke
				(width 0.1)
				(type default)
			)
			(layer "F.Fab")
		)
		(fp_line
			(start -0.12065 -0.2794)
			(end 0.12065 -0.2794)
			(stroke
				(width 0.1)
				(type default)
			)
			(layer "F.Fab")
		)
		(fp_line
			(start -0.12065 -0.305054)
			(end -0.12065 -0.2794)
			(stroke
				(width 0.1)
				(type default)
			)
			(layer "F.Fab")
		)
		(fp_line
			(start -0.67945 0.3048)
			(end -0.67945 -0.305054)
			(stroke
				(width 0.1)
				(type default)
			)
			(layer "F.Fab")
		)
		(fp_line
			(start -0.67945 -0.305054)
			(end -0.12065 -0.305054)
			(stroke
				(width 0.1)
				(type default)
			)
			(layer "F.Fab")
		)
		(pad "1" smd circle
			(at -0.40005 0 180)
			(size 0 0)
			(layers "F.Cu" "F.Mask" "F.Paste")
			(net "PVDD18_S5_P1")
		)
		(pad "2" smd circle
			(at 0.40005 0 180)
			(size 0 0)
			(layers "F.Cu" "F.Mask" "F.Paste")
			(net "SVID_PVDDCR_CPU0_P1_SVD_R")
		)
	)
)
